# BASEBOARD_FAB2 (Tioga Pass) — schematic netlist excerpt (pin names and nets, part order shuffled) for the footprints in the layout excerpt that follows; sources: Cadence DE-HDL packaged netlist, KiCad conversion of Wiwynn_Tioga_Pass_MB.brd

R3N16  RES  1.00K 1% EMPTY  pkg 0402  page 133 : A = P1V05_PCH_STBY ; B = FM_PRSNT_2_5_N
C6U12  CAP  4.7UF 6.3V 10% X6S  pkg 0603  page 221 : A = VSENSE_PVDDQ_ABC_VTT ; B = GND
R2T8  RES  10.0K 1% CHIP  pkg 0402  page 154 : A = P3V3_STBY ; B = SPI_SWITCH_CS0_N

(kicad_pcb
	(version 20260206)
	(generator "pcbnew")
	(generator_version "10.0")
	(general
		(thickness 1.6)
		(legacy_teardrops no)
	)
	(paper "A4")
	(title_block
		(title "Wiwynn_Tioga_Pass_MB.brd")
		(comment 1 "Tioga Pass / footprints 4212-4214 of 4770")
	)
	(layers
		(0 "F.Cu" signal "TOP")
		(4 "In1.Cu" signal "L2GND")
		(6 "In2.Cu" signal "L3")
		(8 "In3.Cu" signal "L4GND")
		(10 "In4.Cu" signal "L5")
		(12 "In5.Cu" signal "L6GND")
		(14 "In6.Cu" signal "L7VCC")
		(16 "In7.Cu" signal "L8VCC")
		(18 "In8.Cu" signal "L9GND")
		(20 "In9.Cu" signal "L10")
		(22 "In10.Cu" signal "L11GND")
		(24 "In11.Cu" signal "L12")
		(26 "In12.Cu" signal "L13GND")
		(2 "B.Cu" signal "BOTTOM")
		(9 "F.Adhes" user "F.Adhesive")
		(11 "B.Adhes" user "B.Adhesive")
		(13 "F.Paste" user "Package Geometry/Pastemask Top")
		(15 "B.Paste" user "Package Geometry/Pastemask Bottom")
		(5 "F.SilkS" user "Ref Des/Silkscreen Top")
		(7 "B.SilkS" user "Ref Des/Silkscreen Bottom")
		(1 "F.Mask" user "Board Geometry/Soldermask Top")
		(3 "B.Mask" user "Board Geometry/Soldermask Bottom")
		(17 "Dwgs.User" user "User.Drawings")
		(19 "Cmts.User" user "User.Comments")
		(21 "Eco1.User" user "User.Eco1")
		(23 "Eco2.User" user "User.Eco2")
		(25 "Edge.Cuts" user "Board Geometry/Outline")
		(27 "Margin" user)
		(31 "F.CrtYd" user "Package Geometry/Place Bound Top")
		(29 "B.CrtYd" user "Package Geometry/Place Bound Bottom")
		(35 "F.Fab" user "Ref Des/Assembly Top")
		(33 "B.Fab" user "Ref Des/Assembly Bottom")
	)
	(footprint ""
		(layer "B.Cu")
		(at 372.4275 -93.091 90)
		(property "Reference" "R3N16"
			(at 0 0 90)
			(layer "B.SilkS")
			(hide yes)
			(effects
				(font
					(size 1.27 1.27)
				)
				(justify mirror)
			)
		)
		(property "Value" ""
			(at 0 0 90)
			(layer "B.Fab")
			(effects
				(font
					(size 1.27 1.27)
				)
				(justify mirror)
			)
		)
		(duplicate_pad_numbers_are_jumpers no)
		(fp_poly
			(pts
				(xy 0.2794 -0.1016) (xy -0.2794 -0.1016) (xy -0.2794 0.9906) (xy 0.2794 0.9906)
			)
			(stroke
				(width 0)
				(type default)
			)
			(fill no)
			(layer "B.CrtYd")
		)
		(fp_line
			(start 0.2794 -0.1016)
			(end 0.2794 0.9906)
			(stroke
				(width 0.1)
				(type default)
			)
			(layer "B.Fab")
		)
		(fp_line
			(start -0.2794 -0.1016)
			(end 0.2794 -0.1016)
			(stroke
				(width 0.1)
				(type default)
			)
			(layer "B.Fab")
		)
		(fp_line
			(start 0.2794 0.9906)
			(end -0.2794 0.9906)
			(stroke
				(width 0.1)
				(type default)
			)
			(layer "B.Fab")
		)
		(fp_line
			(start -0.2794 0.9906)
			(end -0.2794 -0.1016)
			(stroke
				(width 0.1)
				(type default)
			)
			(layer "B.Fab")
		)
		(pad "1" smd rect
			(at 0 0 270)
			(size 0.508 0.508)
			(layers "B.Cu" "B.Mask" "B.Paste")
			(net "P1V05_PCH_STBY")
		)
		(pad "2" smd rect
			(at 0 0.889 270)
			(size 0.508 0.508)
			(layers "B.Cu" "B.Mask" "B.Paste")
			(net "FM_PRSNT_2_5_N")
		)
		(zone
			(layer "B.Cu")
			(hatch none 0.5)
			(connect_pads
				(clearance 0)
			)
			(min_thickness 0.25)
			(keepout
				(tracks allowed)
				(vias not_allowed)
				(pads allowed)
				(copperpour not_allowed)
				(footprints allowed)
			)
			(placement
				(enabled no)
				(sheetname "")
			)
			(fill
				(thermal_gap 0.5)
				(thermal_bridge_width 0.5)
				(island_removal_mode 0)
			)
			(polygon
				(pts
					(xy 372.6815 -93.345) (xy 372.6815 -92.837) (xy 373.0625 -92.837) (xy 373.0625 -93.345)
				)
			)
		)
		(zone
			(layer "B.Cu")
			(hatch none 0.5)
			(connect_pads
				(clearance 0)
			)
			(min_thickness 0.25)
			(keepout
				(tracks not_allowed)
				(vias allowed)
				(pads allowed)
				(copperpour not_allowed)
				(footprints allowed)
			)
			(placement
				(enabled no)
				(sheetname "")
			)
			(fill
				(thermal_gap 0.5)
				(thermal_bridge_width 0.5)
				(island_removal_mode 0)
			)
			(polygon
				(pts
					(xy 373.0625 -93.345) (xy 373.0625 -92.837) (xy 372.6815 -92.837) (xy 372.6815 -93.345)
				)
			)
		)
	)
	(footprint ""
		(layer "B.Cu")
		(at 390.1821 -64.443102 -90)
		(property "Reference" "R2T8"
			(at 0 0 90)
			(layer "B.SilkS")
			(hide yes)
			(effects
				(font
					(size 1.27 1.27)
				)
				(justify mirror)
			)
		)
		(property "Value" ""
			(at 0 0 90)
			(layer "B.Fab")
			(effects
				(font
					(size 1.27 1.27)
				)
				(justify mirror)
			)
		)
		(duplicate_pad_numbers_are_jumpers no)
		(fp_poly
			(pts
				(xy 0.2794 -0.1016) (xy -0.2794 -0.1016) (xy -0.2794 0.9906) (xy 0.2794 0.9906)
			)
			(stroke
				(width 0)
				(type default)
			)
			(fill no)
			(layer "B.CrtYd")
		)
		(fp_line
			(start -0.2794 0.9906)
			(end -0.2794 -0.1016)
			(stroke
				(width 0.1)
				(type default)
			)
			(layer "B.Fab")
		)
		(fp_line
			(start 0.2794 0.9906)
			(end -0.2794 0.9906)
			(stroke
				(width 0.1)
				(type default)
			)
			(layer "B.Fab")
		)
		(fp_line
			(start -0.2794 -0.1016)
			(end 0.2794 -0.1016)
			(stroke
				(width 0.1)
				(type default)
			)
			(layer "B.Fab")
		)
		(fp_line
			(start 0.2794 -0.1016)
			(end 0.2794 0.9906)
			(stroke
				(width 0.1)
				(type default)
			)
			(layer "B.Fab")
		)
		(pad "1" smd rect
			(at 0 0 90)
			(size 0.508 0.508)
			(layers "B.Cu" "B.Mask" "B.Paste")
			(net "P3V3_STBY")
		)
		(pad "2" smd rect
			(at 0 0.889 90)
			(size 0.508 0.508)
			(layers "B.Cu" "B.Mask" "B.Paste")
			(net "SPI_SWITCH_CS0_N")
		)
		(zone
			(layer "B.Cu")
			(hatch none 0.5)
			(connect_pads
				(clearance 0)
			)
			(min_thickness 0.25)
			(keepout
				(tracks not_allowed)
				(vias allowed)
				(pads allowed)
				(copperpour not_allowed)
				(footprints allowed)
			)
			(placement
				(enabled no)
				(sheetname "")
			)
			(fill
				(thermal_gap 0.5)
				(thermal_bridge_width 0.5)
				(island_removal_mode 0)
			)
			(polygon
				(pts
					(xy 389.5471 -64.189102) (xy 389.5471 -64.697102) (xy 389.9281 -64.697102) (xy 389.9281 -64.189102)
				)
			)
		)
		(zone
			(layer "B.Cu")
			(hatch none 0.5)
			(connect_pads
				(clearance 0)
			)
			(min_thickness 0.25)
			(keepout
				(tracks allowed)
				(vias not_allowed)
				(pads allowed)
				(copperpour not_allowed)
				(footprints allowed)
			)
			(placement
				(enabled no)
				(sheetname "")
			)
			(fill
				(thermal_gap 0.5)
				(thermal_bridge_width 0.5)
				(island_removal_mode 0)
			)
			(polygon
				(pts
					(xy 389.9281 -64.189102) (xy 389.9281 -64.697102) (xy 389.5471 -64.697102) (xy 389.5471 -64.189102)
				)
			)
		)
	)
	(footprint ""
		(layer "B.Cu")
		(at 181.5973 -4.4577)
		(property "Reference" "C6U12"
			(at 0 0 0)
			(layer "B.SilkS")
			(hide yes)
			(effects
				(font
					(size 1.27 1.27)
				)
				(justify mirror)
			)
		)
		(property "Value" ""
			(at 0 0 0)
			(layer "B.Fab")
			(effects
				(font
					(size 1.27 1.27)
				)
				(justify mirror)
			)
		)
		(duplicate_pad_numbers_are_jumpers no)
		(fp_poly
			(pts
				(xy 0.4953 -0.2032) (xy -0.4953 -0.2032) (xy -0.4953 1.6002) (xy 0.4953 1.6002)
			)
			(stroke
				(width 0)
				(type default)
			)
			(fill no)
			(layer "B.CrtYd")
		)
		(fp_line
			(start -0.4953 -0.2032)
			(end -0.4953 1.6002)
			(stroke
				(width 0.1)
				(type default)
			)
			(layer "B.Fab")
		)
		(fp_line
			(start -0.4953 1.6002)
			(end 0.4953 1.6002)
			(stroke
				(width 0.1)
				(type default)
			)
			(layer "B.Fab")
		)
		(fp_line
			(start 0.4953 -0.2032)
			(end -0.4953 -0.2032)
			(stroke
				(width 0.1)
				(type default)
			)
			(layer "B.Fab")
		)
		(fp_line
			(start 0.4953 1.6002)
			(end 0.4953 -0.2032)
			(stroke
				(width 0.1)
				(type default)
			)
			(layer "B.Fab")
		)
		(pad "1" smd rect
			(at 0 0 180)
			(size 0.762 0.889)
			(layers "B.Cu" "B.Mask" "B.Paste")
			(net "VSENSE_PVDDQ_ABC_VTT")
		)
		(pad "2" smd rect
			(at 0 1.397 180)
			(size 0.762 0.889)
			(layers "B.Cu" "B.Mask" "B.Paste")
			(net "GND")
		)
		(zone
			(layer "B.Cu")
			(hatch none 0.5)
			(connect_pads
				(clearance 0)
			)
			(min_thickness 0.25)
			(keepout
				(tracks not_allowed)
				(vias allowed)
				(pads allowed)
				(copperpour not_allowed)
				(footprints allowed)
			)
			(placement
				(enabled no)
				(sheetname "")
			)
			(fill
				(thermal_gap 0.5)
				(thermal_bridge_width 0.5)
				(island_removal_mode 0)
			)
			(polygon
				(pts
					(xy 181.9783 -4.0132) (xy 181.2163 -4.0132) (xy 181.2163 -3.5052) (xy 181.9783 -3.5052)
				)
			)
		)
	)
)
